# T6G (Grand Teton) — schematic netlist excerpt (pin names and nets, part order shuffled) for the footprints in the layout excerpt that follows; sources: Cadence DE-HDL packaged netlist, KiCad conversion of 04192023_DAF0TMB3IC0_F0TG_MB_C_brd_V02_OCP.brd

R3531  Q_RES  200K 1% EMPTY  pkg 0402LF  page 148 : A = SMB_PCIE_E1S_ISO_EN ; B = SMB_PCIE_E1S_ISO_EN_R

(kicad_pcb
	(version 20260206)
	(generator "pcbnew")
	(generator_version "10.0")
	(general
		(thickness 1.6)
		(legacy_teardrops no)
	)
	(paper "A4")
	(title_block
		(title "04192023_DAF0TMB3IC0_F0TG_MB_C_brd_V02_OCP.brd")
		(comment 1 "Grand Teton / footprints 780-780 of 8354")
	)
	(layers
		(0 "F.Cu" signal "TOP")
		(4 "In1.Cu" signal "GND")
		(6 "In2.Cu" signal "IN1")
		(8 "In3.Cu" signal "GND1")
		(10 "In4.Cu" signal "IN2")
		(12 "In5.Cu" signal "GND2")
		(14 "In6.Cu" signal "IN3")
		(16 "In7.Cu" signal "GND3")
		(18 "In8.Cu" signal "VCC")
		(20 "In9.Cu" signal "VCC1")
		(22 "In10.Cu" signal "GND4")
		(24 "In11.Cu" signal "IN4")
		(26 "In12.Cu" signal "GND5")
		(28 "In13.Cu" signal "IN5")
		(30 "In14.Cu" signal "GND6")
		(32 "In15.Cu" signal "IN6")
		(34 "In16.Cu" signal "GND7")
		(2 "B.Cu" signal "BOTTOM")
		(9 "F.Adhes" user "F.Adhesive")
		(11 "B.Adhes" user "B.Adhesive")
		(13 "F.Paste" user "Package Geometry/Pastemask Top")
		(15 "B.Paste" user "Package Geometry/Pastemask Bottom")
		(5 "F.SilkS" user "Ref Des/Silkscreen Top")
		(7 "B.SilkS" user "Ref Des/Silkscreen Bottom")
		(1 "F.Mask" user "Board Geometry/Soldermask Top")
		(3 "B.Mask" user "Board Geometry/Soldermask Bottom")
		(17 "Dwgs.User" user "User.Drawings")
		(19 "Cmts.User" user "User.Comments")
		(21 "Eco1.User" user "User.Eco1")
		(23 "Eco2.User" user "User.Eco2")
		(25 "Edge.Cuts" user "Board Geometry/Outline")
		(27 "Margin" user)
		(31 "F.CrtYd" user "Package Geometry/Place Bound Top")
		(29 "B.CrtYd" user "Package Geometry/Place Bound Bottom")
		(35 "F.Fab" user "Ref Des/Assembly Top")
		(33 "B.Fab" user "Ref Des/Assembly Bottom")
	)
	(footprint ""
		(layer "F.Cu")
		(at 210.74888 -44.795948)
		(property "Reference" "R3531"
			(at 0 0 0)
			(layer "F.SilkS")
			(hide yes)
			(effects
				(font
					(size 1.27 1.27)
				)
			)
		)
		(property "Value" ""
			(at 0 0 0)
			(layer "F.Fab")
			(effects
				(font
					(size 1.27 1.27)
				)
			)
		)
		(duplicate_pad_numbers_are_jumpers no)
		(fp_line
			(start -0.7874 -0.4064)
			(end 0.7874 -0.4064)
			(stroke
				(width 0.1524)
				(type default)
			)
			(layer "F.SilkS")
		)
		(fp_line
			(start -0.7874 0.4064)
			(end -0.7874 -0.4064)
			(stroke
				(width 0.1524)
				(type default)
			)
			(layer "F.SilkS")
		)
		(fp_line
			(start 0.7874 -0.4064)
			(end 0.7874 0.4064)
			(stroke
				(width 0.1524)
				(type default)
			)
			(layer "F.SilkS")
		)
		(fp_line
			(start 0.7874 0.4064)
			(end -0.7874 0.4064)
			(stroke
				(width 0.1524)
				(type default)
			)
			(layer "F.SilkS")
		)
		(fp_line
			(start -0.67945 -0.305054)
			(end -0.12065 -0.305054)
			(stroke
				(width 0.1)
				(type default)
			)
			(layer "F.Fab")
		)
		(fp_line
			(start -0.67945 0.3048)
			(end -0.67945 -0.305054)
			(stroke
				(width 0.1)
				(type default)
			)
			(layer "F.Fab")
		)
		(fp_line
			(start -0.12065 -0.305054)
			(end -0.12065 -0.2794)
			(stroke
				(width 0.1)
				(type default)
			)
			(layer "F.Fab")
		)
		(fp_line
			(start -0.12065 -0.2794)
			(end 0.12065 -0.2794)
			(stroke
				(width 0.1)
				(type default)
			)
			(layer "F.Fab")
		)
		(fp_line
			(start -0.12065 0.2794)
			(end -0.12065 0.3048)
			(stroke
				(width 0.1)
				(type default)
			)
			(layer "F.Fab")
		)
		(fp_line
			(start -0.12065 0.3048)
			(end -0.67945 0.3048)
			(stroke
				(width 0.1)
				(type default)
			)
			(layer "F.Fab")
		)
		(fp_line
			(start 0.120396 0.2794)
			(end -0.12065 0.2794)
			(stroke
				(width 0.1)
				(type default)
			)
			(layer "F.Fab")
		)
		(fp_line
			(start 0.120396 0.3048)
			(end 0.120396 0.2794)
			(stroke
				(width 0.1)
				(type default)
			)
			(layer "F.Fab")
		)
		(fp_line
			(start 0.12065 -0.3048)
			(end 0.67945 -0.3048)
			(stroke
				(width 0.1)
				(type default)
			)
			(layer "F.Fab")
		)
		(fp_line
			(start 0.12065 -0.2794)
			(end 0.12065 -0.3048)
			(stroke
				(width 0.1)
				(type default)
			)
			(layer "F.Fab")
		)
		(fp_line
			(start 0.67945 -0.3048)
			(end 0.67945 0.3048)
			(stroke
				(width 0.1)
				(type default)
			)
			(layer "F.Fab")
		)
		(fp_line
			(start 0.67945 0.3048)
			(end 0.120396 0.3048)
			(stroke
				(width 0.1)
				(type default)
			)
			(layer "F.Fab")
		)
		(pad "1" smd circle
			(at -0.40005 0)
			(size 0 0)
			(layers "F.Cu" "F.Mask" "F.Paste")
			(net "SMB_PCIE_E1S_ISO_EN")
		)
		(pad "2" smd circle
			(at 0.40005 0)
			(size 0 0)
			(layers "F.Cu" "F.Mask" "F.Paste")
			(net "SMB_PCIE_E1S_ISO_EN_R")
		)
	)
)
